# BASEBOARD_FAB2 (Tioga Pass) — schematic netlist excerpt (pin names and nets, part order shuffled) for the footprints in the layout excerpt that follows; sources: Cadence DE-HDL packaged netlist, KiCad conversion of Wiwynn_Tioga_Pass_MB.brd

C8L4  CAP  100UF 4V 20% X5R  pkg 0805  page 230 : A = PVTT_KLM ; B = GND
R7P5  RES  150.0 1% CHIP  pkg 0402  page 152 : A = H_CPU1_MEMGHJ_MEMHOT_G_N ; B = PVCCIO_CPU1
R1E8  RES  100.0 1% CHIP  pkg 0402  page 209 : A = VSENSE_PVCCIN_CPU1_N ; B = GND

(kicad_pcb
	(version 20260206)
	(generator "pcbnew")
	(generator_version "10.0")
	(general
		(thickness 1.6)
		(legacy_teardrops no)
	)
	(paper "A4")
	(title_block
		(title "Wiwynn_Tioga_Pass_MB.brd")
		(comment 1 "Tioga Pass / footprints 4125-4127 of 4770")
	)
	(layers
		(0 "F.Cu" signal "TOP")
		(4 "In1.Cu" signal "L2GND")
		(6 "In2.Cu" signal "L3")
		(8 "In3.Cu" signal "L4GND")
		(10 "In4.Cu" signal "L5")
		(12 "In5.Cu" signal "L6GND")
		(14 "In6.Cu" signal "L7VCC")
		(16 "In7.Cu" signal "L8VCC")
		(18 "In8.Cu" signal "L9GND")
		(20 "In9.Cu" signal "L10")
		(22 "In10.Cu" signal "L11GND")
		(24 "In11.Cu" signal "L12")
		(26 "In12.Cu" signal "L13GND")
		(2 "B.Cu" signal "BOTTOM")
		(9 "F.Adhes" user "F.Adhesive")
		(11 "B.Adhes" user "B.Adhesive")
		(13 "F.Paste" user "Package Geometry/Pastemask Top")
		(15 "B.Paste" user "Package Geometry/Pastemask Bottom")
		(5 "F.SilkS" user "Ref Des/Silkscreen Top")
		(7 "B.SilkS" user "Ref Des/Silkscreen Bottom")
		(1 "F.Mask" user "Board Geometry/Soldermask Top")
		(3 "B.Mask" user "Board Geometry/Soldermask Bottom")
		(17 "Dwgs.User" user "User.Drawings")
		(19 "Cmts.User" user "User.Comments")
		(21 "Eco1.User" user "User.Eco1")
		(23 "Eco2.User" user "User.Eco2")
		(25 "Edge.Cuts" user "Board Geometry/Outline")
		(27 "Margin" user)
		(31 "F.CrtYd" user "Package Geometry/Place Bound Top")
		(29 "B.CrtYd" user "Package Geometry/Place Bound Bottom")
		(35 "F.Fab" user "Ref Des/Assembly Top")
		(33 "B.Fab" user "Ref Des/Assembly Bottom")
	)
	(footprint ""
		(layer "B.Cu")
		(at 64.262 -64.7954 180)
		(property "Reference" "R1E8"
			(at 0 0 0)
			(layer "B.SilkS")
			(hide yes)
			(effects
				(font
					(size 1.27 1.27)
				)
				(justify mirror)
			)
		)
		(property "Value" ""
			(at 0 0 0)
			(layer "B.Fab")
			(effects
				(font
					(size 1.27 1.27)
				)
				(justify mirror)
			)
		)
		(duplicate_pad_numbers_are_jumpers no)
		(fp_poly
			(pts
				(xy 0.2794 -0.1016) (xy -0.2794 -0.1016) (xy -0.2794 0.9906) (xy 0.2794 0.9906)
			)
			(stroke
				(width 0)
				(type default)
			)
			(fill no)
			(layer "B.CrtYd")
		)
		(fp_line
			(start 0.2794 0.9906)
			(end -0.2794 0.9906)
			(stroke
				(width 0.1)
				(type default)
			)
			(layer "B.Fab")
		)
		(fp_line
			(start 0.2794 -0.1016)
			(end 0.2794 0.9906)
			(stroke
				(width 0.1)
				(type default)
			)
			(layer "B.Fab")
		)
		(fp_line
			(start -0.2794 0.9906)
			(end -0.2794 -0.1016)
			(stroke
				(width 0.1)
				(type default)
			)
			(layer "B.Fab")
		)
		(fp_line
			(start -0.2794 -0.1016)
			(end 0.2794 -0.1016)
			(stroke
				(width 0.1)
				(type default)
			)
			(layer "B.Fab")
		)
		(pad "1" smd rect
			(at 0 0)
			(size 0.508 0.508)
			(layers "B.Cu" "B.Mask" "B.Paste")
			(net "VSENSE_PVCCIN_CPU1_N")
		)
		(pad "2" smd rect
			(at 0 0.889)
			(size 0.508 0.508)
			(layers "B.Cu" "B.Mask" "B.Paste")
			(net "GND")
		)
		(zone
			(layer "B.Cu")
			(hatch none 0.5)
			(connect_pads
				(clearance 0)
			)
			(min_thickness 0.25)
			(keepout
				(tracks not_allowed)
				(vias allowed)
				(pads allowed)
				(copperpour not_allowed)
				(footprints allowed)
			)
			(placement
				(enabled no)
				(sheetname "")
			)
			(fill
				(thermal_gap 0.5)
				(thermal_bridge_width 0.5)
				(island_removal_mode 0)
			)
			(polygon
				(pts
					(xy 64.008 -65.4304) (xy 64.516 -65.4304) (xy 64.516 -65.0494) (xy 64.008 -65.0494)
				)
			)
		)
		(zone
			(layer "B.Cu")
			(hatch none 0.5)
			(connect_pads
				(clearance 0)
			)
			(min_thickness 0.25)
			(keepout
				(tracks allowed)
				(vias not_allowed)
				(pads allowed)
				(copperpour not_allowed)
				(footprints allowed)
			)
			(placement
				(enabled no)
				(sheetname "")
			)
			(fill
				(thermal_gap 0.5)
				(thermal_bridge_width 0.5)
				(island_removal_mode 0)
			)
			(polygon
				(pts
					(xy 64.008 -65.0494) (xy 64.516 -65.0494) (xy 64.516 -65.4304) (xy 64.008 -65.4304)
				)
			)
		)
	)
	(footprint ""
		(layer "B.Cu")
		(at 96.45904 -157.02788 -90)
		(property "Reference" "C8L4"
			(at -1.47828 0.78994 0)
			(unlocked yes)
			(layer "B.SilkS")
			(effects
				(font
					(size 0.4064 0.254)
					(thickness 0.1524)
				)
				(justify mirror)
			)
		)
		(property "Value" ""
			(at 0 0 90)
			(layer "B.Fab")
			(effects
				(font
					(size 1.27 1.27)
				)
				(justify mirror)
			)
		)
		(duplicate_pad_numbers_are_jumpers no)
		(fp_poly
			(pts
				(xy 0.7239 -0.2159) (xy -0.7239 -0.2159) (xy -0.7239 1.9939) (xy 0.7239 1.9939)
			)
			(stroke
				(width 0)
				(type default)
			)
			(fill no)
			(layer "B.CrtYd")
		)
		(fp_line
			(start -0.7239 1.9939)
			(end -0.7239 -0.2159)
			(stroke
				(width 0.1)
				(type default)
			)
			(layer "B.Fab")
		)
		(fp_line
			(start 0.7239 1.9939)
			(end -0.7239 1.9939)
			(stroke
				(width 0.1)
				(type default)
			)
			(layer "B.Fab")
		)
		(fp_line
			(start -0.7239 -0.2159)
			(end 0.7239 -0.2159)
			(stroke
				(width 0.1)
				(type default)
			)
			(layer "B.Fab")
		)
		(fp_line
			(start 0.7239 -0.2159)
			(end 0.7239 1.9939)
			(stroke
				(width 0.1)
				(type default)
			)
			(layer "B.Fab")
		)
		(pad "1" smd rect
			(at 0 0 90)
			(size 1.27 1.016)
			(layers "B.Cu" "B.Mask" "B.Paste")
			(net "PVTT_KLM")
		)
		(pad "2" smd rect
			(at 0 1.778 90)
			(size 1.27 1.016)
			(layers "B.Cu" "B.Mask" "B.Paste")
			(net "GND")
		)
		(zone
			(layer "B.Cu")
			(hatch none 0.5)
			(connect_pads
				(clearance 0)
			)
			(min_thickness 0.25)
			(keepout
				(tracks not_allowed)
				(vias allowed)
				(pads allowed)
				(copperpour not_allowed)
				(footprints allowed)
			)
			(placement
				(enabled no)
				(sheetname "")
			)
			(fill
				(thermal_gap 0.5)
				(thermal_bridge_width 0.5)
				(island_removal_mode 0)
			)
			(polygon
				(pts
					(xy 95.95104 -156.39288) (xy 95.95104 -157.66288) (xy 95.18904 -157.66288) (xy 95.18904 -156.39288)
				)
			)
		)
	)
	(footprint ""
		(layer "B.Cu")
		(at 117.094 -81.483962)
		(property "Reference" "R7P5"
			(at 0 0 0)
			(layer "B.SilkS")
			(hide yes)
			(effects
				(font
					(size 1.27 1.27)
				)
				(justify mirror)
			)
		)
		(property "Value" ""
			(at 0 0 0)
			(layer "B.Fab")
			(effects
				(font
					(size 1.27 1.27)
				)
				(justify mirror)
			)
		)
		(duplicate_pad_numbers_are_jumpers no)
		(fp_poly
			(pts
				(xy 0.2794 -0.1016) (xy -0.2794 -0.1016) (xy -0.2794 0.9906) (xy 0.2794 0.9906)
			)
			(stroke
				(width 0)
				(type default)
			)
			(fill no)
			(layer "B.CrtYd")
		)
		(fp_line
			(start -0.2794 -0.1016)
			(end 0.2794 -0.1016)
			(stroke
				(width 0.1)
				(type default)
			)
			(layer "B.Fab")
		)
		(fp_line
			(start -0.2794 0.9906)
			(end -0.2794 -0.1016)
			(stroke
				(width 0.1)
				(type default)
			)
			(layer "B.Fab")
		)
		(fp_line
			(start 0.2794 -0.1016)
			(end 0.2794 0.9906)
			(stroke
				(width 0.1)
				(type default)
			)
			(layer "B.Fab")
		)
		(fp_line
			(start 0.2794 0.9906)
			(end -0.2794 0.9906)
			(stroke
				(width 0.1)
				(type default)
			)
			(layer "B.Fab")
		)
		(pad "1" smd rect
			(at 0 0 180)
			(size 0.508 0.508)
			(layers "B.Cu" "B.Mask" "B.Paste")
			(net "H_CPU1_MEMGHJ_MEMHOT_G_N")
		)
		(pad "2" smd rect
			(at 0 0.889 180)
			(size 0.508 0.508)
			(layers "B.Cu" "B.Mask" "B.Paste")
			(net "PVCCIO_CPU1")
		)
		(zone
			(layer "B.Cu")
			(hatch none 0.5)
			(connect_pads
				(clearance 0)
			)
			(min_thickness 0.25)
			(keepout
				(tracks allowed)
				(vias not_allowed)
				(pads allowed)
				(copperpour not_allowed)
				(footprints allowed)
			)
			(placement
				(enabled no)
				(sheetname "")
			)
			(fill
				(thermal_gap 0.5)
				(thermal_bridge_width 0.5)
				(island_removal_mode 0)
			)
			(polygon
				(pts
					(xy 117.348 -81.229962) (xy 116.84 -81.229962) (xy 116.84 -80.848962) (xy 117.348 -80.848962)
				)
			)
		)
		(zone
			(layer "B.Cu")
			(hatch none 0.5)
			(connect_pads
				(clearance 0)
			)
			(min_thickness 0.25)
			(keepout
				(tracks not_allowed)
				(vias allowed)
				(pads allowed)
				(copperpour not_allowed)
				(footprints allowed)
			)
			(placement
				(enabled no)
				(sheetname "")
			)
			(fill
				(thermal_gap 0.5)
				(thermal_bridge_width 0.5)
				(island_removal_mode 0)
			)
			(polygon
				(pts
					(xy 117.348 -80.848962) (xy 116.84 -80.848962) (xy 116.84 -81.229962) (xy 117.348 -81.229962)
				)
			)
		)
	)
)
